# T6G (Grand Teton) — schematic netlist excerpt (pin names and nets, part order shuffled) for the footprints in the layout excerpt that follows; sources: Cadence DE-HDL packaged netlist, KiCad conversion of 04192023_DAF0TMB3IC0_F0TG_MB_C_brd_V02_OCP.brd

PC1322  Q_CAP  100PF 50V 5% X7R  pkg 0402  page 141 : A = P3V3_OCP_GATE_PU207_2 ; B = GND
PC318  Q_CAP  560PF 50V 10% EMPTY  pkg C0402  page 213 : A = SW_PVDDCR_CPU0_P1_SW5 ; B = SW_PVDDCR_CPU0_P1_SW5_RC

(kicad_pcb
	(version 20260206)
	(generator "pcbnew")
	(generator_version "10.0")
	(general
		(thickness 1.6)
		(legacy_teardrops no)
	)
	(paper "A4")
	(title_block
		(title "04192023_DAF0TMB3IC0_F0TG_MB_C_brd_V02_OCP.brd")
		(comment 1 "Grand Teton / footprints 3772-3773 of 8354")
	)
	(layers
		(0 "F.Cu" signal "TOP")
		(4 "In1.Cu" signal "GND")
		(6 "In2.Cu" signal "IN1")
		(8 "In3.Cu" signal "GND1")
		(10 "In4.Cu" signal "IN2")
		(12 "In5.Cu" signal "GND2")
		(14 "In6.Cu" signal "IN3")
		(16 "In7.Cu" signal "GND3")
		(18 "In8.Cu" signal "VCC")
		(20 "In9.Cu" signal "VCC1")
		(22 "In10.Cu" signal "GND4")
		(24 "In11.Cu" signal "IN4")
		(26 "In12.Cu" signal "GND5")
		(28 "In13.Cu" signal "IN5")
		(30 "In14.Cu" signal "GND6")
		(32 "In15.Cu" signal "IN6")
		(34 "In16.Cu" signal "GND7")
		(2 "B.Cu" signal "BOTTOM")
		(9 "F.Adhes" user "F.Adhesive")
		(11 "B.Adhes" user "B.Adhesive")
		(13 "F.Paste" user "Package Geometry/Pastemask Top")
		(15 "B.Paste" user "Package Geometry/Pastemask Bottom")
		(5 "F.SilkS" user "Ref Des/Silkscreen Top")
		(7 "B.SilkS" user "Ref Des/Silkscreen Bottom")
		(1 "F.Mask" user "Board Geometry/Soldermask Top")
		(3 "B.Mask" user "Board Geometry/Soldermask Bottom")
		(17 "Dwgs.User" user "User.Drawings")
		(19 "Cmts.User" user "User.Comments")
		(21 "Eco1.User" user "User.Eco1")
		(23 "Eco2.User" user "User.Eco2")
		(25 "Edge.Cuts" user "Board Geometry/Outline")
		(27 "Margin" user)
		(31 "F.CrtYd" user "Package Geometry/Place Bound Top")
		(29 "B.CrtYd" user "Package Geometry/Place Bound Bottom")
		(35 "F.Fab" user "Ref Des/Assembly Top")
		(33 "B.Fab" user "Ref Des/Assembly Bottom")
	)
	(footprint ""
		(layer "F.Cu")
		(at 97.177352 -71.21398)
		(property "Reference" "PC1322"
			(at 0 0 0)
			(layer "F.SilkS")
			(hide yes)
			(effects
				(font
					(size 1.27 1.27)
				)
			)
		)
		(property "Value" ""
			(at 0 0 0)
			(layer "F.Fab")
			(effects
				(font
					(size 1.27 1.27)
				)
			)
		)
		(duplicate_pad_numbers_are_jumpers no)
		(fp_line
			(start -0.7874 -0.4064)
			(end 0.7874 -0.4064)
			(stroke
				(width 0.1524)
				(type default)
			)
			(layer "F.SilkS")
		)
		(fp_line
			(start -0.7874 0.4064)
			(end -0.7874 -0.4064)
			(stroke
				(width 0.1524)
				(type default)
			)
			(layer "F.SilkS")
		)
		(fp_line
			(start 0.7874 -0.4064)
			(end 0.7874 0.4064)
			(stroke
				(width 0.1524)
				(type default)
			)
			(layer "F.SilkS")
		)
		(fp_line
			(start 0.7874 0.4064)
			(end -0.7874 0.4064)
			(stroke
				(width 0.1524)
				(type default)
			)
			(layer "F.SilkS")
		)
		(fp_line
			(start -0.67945 -0.305054)
			(end -0.12065 -0.305054)
			(stroke
				(width 0.1)
				(type default)
			)
			(layer "F.Fab")
		)
		(fp_line
			(start -0.67945 0.3048)
			(end -0.67945 -0.305054)
			(stroke
				(width 0.1)
				(type default)
			)
			(layer "F.Fab")
		)
		(fp_line
			(start -0.12065 -0.305054)
			(end -0.12065 -0.2794)
			(stroke
				(width 0.1)
				(type default)
			)
			(layer "F.Fab")
		)
		(fp_line
			(start -0.12065 -0.2794)
			(end 0.12065 -0.2794)
			(stroke
				(width 0.1)
				(type default)
			)
			(layer "F.Fab")
		)
		(fp_line
			(start -0.12065 0.2794)
			(end -0.12065 0.3048)
			(stroke
				(width 0.1)
				(type default)
			)
			(layer "F.Fab")
		)
		(fp_line
			(start -0.12065 0.3048)
			(end -0.67945 0.3048)
			(stroke
				(width 0.1)
				(type default)
			)
			(layer "F.Fab")
		)
		(fp_line
			(start 0.120396 0.2794)
			(end -0.12065 0.2794)
			(stroke
				(width 0.1)
				(type default)
			)
			(layer "F.Fab")
		)
		(fp_line
			(start 0.120396 0.3048)
			(end 0.120396 0.2794)
			(stroke
				(width 0.1)
				(type default)
			)
			(layer "F.Fab")
		)
		(fp_line
			(start 0.12065 -0.3048)
			(end 0.67945 -0.3048)
			(stroke
				(width 0.1)
				(type default)
			)
			(layer "F.Fab")
		)
		(fp_line
			(start 0.12065 -0.2794)
			(end 0.12065 -0.3048)
			(stroke
				(width 0.1)
				(type default)
			)
			(layer "F.Fab")
		)
		(fp_line
			(start 0.67945 -0.3048)
			(end 0.67945 0.3048)
			(stroke
				(width 0.1)
				(type default)
			)
			(layer "F.Fab")
		)
		(fp_line
			(start 0.67945 0.3048)
			(end 0.120396 0.3048)
			(stroke
				(width 0.1)
				(type default)
			)
			(layer "F.Fab")
		)
		(pad "1" smd circle
			(at -0.40005 0)
			(size 0 0)
			(layers "F.Cu" "F.Mask" "F.Paste")
			(net "P3V3_OCP_GATE_PU207_2")
		)
		(pad "2" smd circle
			(at 0.40005 0)
			(size 0 0)
			(layers "F.Cu" "F.Mask" "F.Paste")
			(net "GND")
		)
	)
	(footprint ""
		(layer "F.Cu")
		(at 77.654912 -180.630068)
		(property "Reference" "PC318"
			(at 0 0 0)
			(layer "F.SilkS")
			(hide yes)
			(effects
				(font
					(size 1.27 1.27)
				)
			)
		)
		(property "Value" ""
			(at 0 0 0)
			(layer "F.Fab")
			(effects
				(font
					(size 1.27 1.27)
				)
			)
		)
		(duplicate_pad_numbers_are_jumpers no)
		(fp_line
			(start -0.7874 -0.4064)
			(end 0.7874 -0.4064)
			(stroke
				(width 0.1524)
				(type default)
			)
			(layer "F.SilkS")
		)
		(fp_line
			(start -0.7874 0.4064)
			(end -0.7874 -0.4064)
			(stroke
				(width 0.1524)
				(type default)
			)
			(layer "F.SilkS")
		)
		(fp_line
			(start 0.7874 -0.4064)
			(end 0.7874 0.4064)
			(stroke
				(width 0.1524)
				(type default)
			)
			(layer "F.SilkS")
		)
		(fp_line
			(start 0.7874 0.4064)
			(end -0.7874 0.4064)
			(stroke
				(width 0.1524)
				(type default)
			)
			(layer "F.SilkS")
		)
		(fp_line
			(start -0.67945 -0.305054)
			(end -0.12065 -0.305054)
			(stroke
				(width 0.1)
				(type default)
			)
			(layer "F.Fab")
		)
		(fp_line
			(start -0.67945 0.3048)
			(end -0.67945 -0.305054)
			(stroke
				(width 0.1)
				(type default)
			)
			(layer "F.Fab")
		)
		(fp_line
			(start -0.12065 -0.305054)
			(end -0.12065 -0.2794)
			(stroke
				(width 0.1)
				(type default)
			)
			(layer "F.Fab")
		)
		(fp_line
			(start -0.12065 -0.2794)
			(end 0.12065 -0.2794)
			(stroke
				(width 0.1)
				(type default)
			)
			(layer "F.Fab")
		)
		(fp_line
			(start -0.12065 0.2794)
			(end -0.12065 0.3048)
			(stroke
				(width 0.1)
				(type default)
			)
			(layer "F.Fab")
		)
		(fp_line
			(start -0.12065 0.3048)
			(end -0.67945 0.3048)
			(stroke
				(width 0.1)
				(type default)
			)
			(layer "F.Fab")
		)
		(fp_line
			(start 0.120396 0.2794)
			(end -0.12065 0.2794)
			(stroke
				(width 0.1)
				(type default)
			)
			(layer "F.Fab")
		)
		(fp_line
			(start 0.120396 0.3048)
			(end 0.120396 0.2794)
			(stroke
				(width 0.1)
				(type default)
			)
			(layer "F.Fab")
		)
		(fp_line
			(start 0.12065 -0.3048)
			(end 0.67945 -0.3048)
			(stroke
				(width 0.1)
				(type default)
			)
			(layer "F.Fab")
		)
		(fp_line
			(start 0.12065 -0.2794)
			(end 0.12065 -0.3048)
			(stroke
				(width 0.1)
				(type default)
			)
			(layer "F.Fab")
		)
		(fp_line
			(start 0.67945 -0.3048)
			(end 0.67945 0.3048)
			(stroke
				(width 0.1)
				(type default)
			)
			(layer "F.Fab")
		)
		(fp_line
			(start 0.67945 0.3048)
			(end 0.120396 0.3048)
			(stroke
				(width 0.1)
				(type default)
			)
			(layer "F.Fab")
		)
		(pad "1" smd circle
			(at -0.40005 0)
			(size 0 0)
			(layers "F.Cu" "F.Mask" "F.Paste")
			(net "SW_PVDDCR_CPU0_P1_SW5")
		)
		(pad "2" smd circle
			(at 0.40005 0)
			(size 0 0)
			(layers "F.Cu" "F.Mask" "F.Paste")
			(net "SW_PVDDCR_CPU0_P1_SW5_RC")
		)
	)
)
